# T6G (Grand Teton) — schematic netlist excerpt (pin names and nets, part order shuffled) for the footprints in the layout excerpt that follows; sources: Cadence DE-HDL packaged netlist, KiCad conversion of 04192023_DAF0TMB3IC0_F0TG_MB_C_brd_V02_OCP.brd

R2222  Q_RES  1K 1% EMPTY  pkg 0402LF  page 268 : A = A_P12V_STBY_FP_TRIGGER ; B = GND

U53  SN74AVC4T774PWR  IC  pkg TSSOP16XC  page 77
  DIR1  = PVDD18_S5_P0
  DIR2  = PVDD18_S5_P0
  A1  = SPI_CPU0_CS0_N
  A2  = SPI_CPU0_CLK
  A3  = SPI_CPU0_CS1_N
  A4  = SPI_CPU0_TPM_CS_N
  DIR3  = PVDD18_S5_P0
  DIR4  = PVDD18_S5_P0
  OE  = ROM_SD_LS_OE
  GND  = GND
  B4  = SPI_CPU0_LVC3_R_TPM_CS_N
  B3  = SPI_CPU0_LVC3_CS1_N
  B2  = SPI_CPU0_LVC3_CLK
  B1  = SPI_CPU0_LVC3_CS0_N
  VCCB  = P3V3_AUX
  VCCA  = PVDD18_S5_P0

(kicad_pcb
	(version 20260206)
	(generator "pcbnew")
	(generator_version "10.0")
	(general
		(thickness 1.6)
		(legacy_teardrops no)
	)
	(paper "A4")
	(title_block
		(title "04192023_DAF0TMB3IC0_F0TG_MB_C_brd_V02_OCP.brd")
		(comment 1 "Grand Teton / footprints 2163-2164 of 8354")
	)
	(layers
		(0 "F.Cu" signal "TOP")
		(4 "In1.Cu" signal "GND")
		(6 "In2.Cu" signal "IN1")
		(8 "In3.Cu" signal "GND1")
		(10 "In4.Cu" signal "IN2")
		(12 "In5.Cu" signal "GND2")
		(14 "In6.Cu" signal "IN3")
		(16 "In7.Cu" signal "GND3")
		(18 "In8.Cu" signal "VCC")
		(20 "In9.Cu" signal "VCC1")
		(22 "In10.Cu" signal "GND4")
		(24 "In11.Cu" signal "IN4")
		(26 "In12.Cu" signal "GND5")
		(28 "In13.Cu" signal "IN5")
		(30 "In14.Cu" signal "GND6")
		(32 "In15.Cu" signal "IN6")
		(34 "In16.Cu" signal "GND7")
		(2 "B.Cu" signal "BOTTOM")
		(9 "F.Adhes" user "F.Adhesive")
		(11 "B.Adhes" user "B.Adhesive")
		(13 "F.Paste" user "Package Geometry/Pastemask Top")
		(15 "B.Paste" user "Package Geometry/Pastemask Bottom")
		(5 "F.SilkS" user "Ref Des/Silkscreen Top")
		(7 "B.SilkS" user "Ref Des/Silkscreen Bottom")
		(1 "F.Mask" user "Board Geometry/Soldermask Top")
		(3 "B.Mask" user "Board Geometry/Soldermask Bottom")
		(17 "Dwgs.User" user "User.Drawings")
		(19 "Cmts.User" user "User.Comments")
		(21 "Eco1.User" user "User.Eco1")
		(23 "Eco2.User" user "User.Eco2")
		(25 "Edge.Cuts" user "Board Geometry/Outline")
		(27 "Margin" user)
		(31 "F.CrtYd" user "Package Geometry/Place Bound Top")
		(29 "B.CrtYd" user "Package Geometry/Place Bound Bottom")
		(35 "F.Fab" user "Ref Des/Assembly Top")
		(33 "B.Fab" user "Ref Des/Assembly Bottom")
	)
	(footprint ""
		(layer "F.Cu")
		(at 258.99237 -132.980176 180)
		(property "Reference" "U53"
			(at 1.11506 -3.372104 0)
			(unlocked yes)
			(layer "F.SilkS")
			(effects
				(font
					(size 0.7874 0.5842)
					(thickness 0.1524)
				)
				(justify left)
			)
		)
		(property "Value" ""
			(at 0 0 180)
			(layer "F.Fab")
			(effects
				(font
					(size 1.27 1.27)
				)
			)
		)
		(duplicate_pad_numbers_are_jumpers no)
		(fp_line
			(start 1.868932 2.549906)
			(end 1.868932 -2.549906)
			(stroke
				(width 0.1524)
				(type default)
			)
			(layer "F.SilkS")
		)
		(fp_line
			(start 1.868932 -2.549906)
			(end 1.025906 -2.549906)
			(stroke
				(width 0.1524)
				(type default)
			)
			(layer "F.SilkS")
		)
		(fp_line
			(start 1.025906 -2.549906)
			(end 0 -1.524)
			(stroke
				(width 0.1524)
				(type default)
			)
			(layer "F.SilkS")
		)
		(fp_line
			(start 0 -1.524)
			(end -1.025906 -2.549906)
			(stroke
				(width 0.1524)
				(type default)
			)
			(layer "F.SilkS")
		)
		(fp_line
			(start -1.025906 -2.549906)
			(end -1.868932 -2.549906)
			(stroke
				(width 0.1524)
				(type default)
			)
			(layer "F.SilkS")
		)
		(fp_line
			(start -1.868932 2.549906)
			(end 1.868932 2.549906)
			(stroke
				(width 0.1524)
				(type default)
			)
			(layer "F.SilkS")
		)
		(fp_line
			(start -1.868932 -2.549906)
			(end -1.868932 2.549906)
			(stroke
				(width 0.1524)
				(type default)
			)
			(layer "F.SilkS")
		)
		(fp_poly
			(pts
				(xy -2.802128 -2.775966) (xy -3.310128 -3.791966) (xy -2.294128 -3.791966)
			)
			(stroke
				(width 0)
				(type default)
			)
			(fill yes)
			(layer "F.SilkS")
		)
		(fp_line
			(start 2.249932 2.549906)
			(end 2.249932 -2.549906)
			(stroke
				(width 0.1)
				(type default)
			)
			(layer "F.Fab")
		)
		(fp_line
			(start 2.249932 -2.549906)
			(end -2.249932 -2.549906)
			(stroke
				(width 0.1)
				(type default)
			)
			(layer "F.Fab")
		)
		(fp_line
			(start -2.249932 2.549906)
			(end 2.249932 2.549906)
			(stroke
				(width 0.1)
				(type default)
			)
			(layer "F.Fab")
		)
		(fp_line
			(start -2.249932 -2.549906)
			(end -2.249932 2.549906)
			(stroke
				(width 0.1)
				(type default)
			)
			(layer "F.Fab")
		)
		(fp_poly
			(pts
				(xy -4.7752 -1.787398) (xy -4.7752 -2.803398) (xy -3.7592 -2.295398)
			)
			(stroke
				(width 0)
				(type default)
			)
			(fill yes)
			(layer "F.Fab")
		)
		(pad "1" smd rect
			(at -2.800096 -2.275078 90)
			(size 0.3556 1.6002)
			(layers "F.Cu" "F.Mask" "F.Paste")
			(net "PVDD18_S5_P0")
		)
		(pad "2" smd rect
			(at -2.800096 -1.625092 90)
			(size 0.3556 1.6002)
			(layers "F.Cu" "F.Mask" "F.Paste")
			(net "PVDD18_S5_P0")
		)
		(pad "3" smd rect
			(at -2.800096 -0.975106 90)
			(size 0.3556 1.6002)
			(layers "F.Cu" "F.Mask" "F.Paste")
			(net "SPI_CPU0_CS0_N")
		)
		(pad "4" smd rect
			(at -2.800096 -0.32512 90)
			(size 0.3556 1.6002)
			(layers "F.Cu" "F.Mask" "F.Paste")
			(net "SPI_CPU0_CLK")
		)
		(pad "5" smd rect
			(at -2.800096 0.32512 90)
			(size 0.3556 1.6002)
			(layers "F.Cu" "F.Mask" "F.Paste")
			(net "SPI_CPU0_CS1_N")
		)
		(pad "6" smd rect
			(at -2.800096 0.975106 90)
			(size 0.3556 1.6002)
			(layers "F.Cu" "F.Mask" "F.Paste")
			(net "SPI_CPU0_TPM_CS_N")
		)
		(pad "7" smd rect
			(at -2.800096 1.625092 90)
			(size 0.3556 1.6002)
			(layers "F.Cu" "F.Mask" "F.Paste")
			(net "PVDD18_S5_P0")
		)
		(pad "8" smd rect
			(at -2.800096 2.275078 90)
			(size 0.3556 1.6002)
			(layers "F.Cu" "F.Mask" "F.Paste")
			(net "PVDD18_S5_P0")
		)
		(pad "9" smd rect
			(at 2.800096 2.275078 90)
			(size 0.3556 1.6002)
			(layers "F.Cu" "F.Mask" "F.Paste")
			(net "ROM_SD_LS_OE")
		)
		(pad "10" smd rect
			(at 2.800096 1.625092 90)
			(size 0.3556 1.6002)
			(layers "F.Cu" "F.Mask" "F.Paste")
			(net "GND")
		)
		(pad "11" smd rect
			(at 2.800096 0.975106 90)
			(size 0.3556 1.6002)
			(layers "F.Cu" "F.Mask" "F.Paste")
			(net "SPI_CPU0_LVC3_R_TPM_CS_N")
		)
		(pad "12" smd rect
			(at 2.800096 0.32512 90)
			(size 0.3556 1.6002)
			(layers "F.Cu" "F.Mask" "F.Paste")
			(net "SPI_CPU0_LVC3_CS1_N")
		)
		(pad "13" smd rect
			(at 2.800096 -0.32512 90)
			(size 0.3556 1.6002)
			(layers "F.Cu" "F.Mask" "F.Paste")
			(net "SPI_CPU0_LVC3_CLK")
		)
		(pad "14" smd rect
			(at 2.800096 -0.975106 90)
			(size 0.3556 1.6002)
			(layers "F.Cu" "F.Mask" "F.Paste")
			(net "SPI_CPU0_LVC3_CS0_N")
		)
		(pad "15" smd rect
			(at 2.800096 -1.625092 90)
			(size 0.3556 1.6002)
			(layers "F.Cu" "F.Mask" "F.Paste")
			(net "P3V3_AUX")
		)
		(pad "16" smd rect
			(at 2.800096 -2.275078 90)
			(size 0.3556 1.6002)
			(layers "F.Cu" "F.Mask" "F.Paste")
			(net "PVDD18_S5_P0")
		)
	)
	(footprint ""
		(layer "F.Cu")
		(at 150.368762 -120.485662 180)
		(property "Reference" "R2222"
			(at 0 0 180)
			(layer "F.SilkS")
			(hide yes)
			(effects
				(font
					(size 1.27 1.27)
				)
			)
		)
		(property "Value" ""
			(at 0 0 180)
			(layer "F.Fab")
			(effects
				(font
					(size 1.27 1.27)
				)
			)
		)
		(duplicate_pad_numbers_are_jumpers no)
		(fp_line
			(start 0.7874 0.4064)
			(end -0.7874 0.4064)
			(stroke
				(width 0.1524)
				(type default)
			)
			(layer "F.SilkS")
		)
		(fp_line
			(start 0.7874 -0.4064)
			(end 0.7874 0.4064)
			(stroke
				(width 0.1524)
				(type default)
			)
			(layer "F.SilkS")
		)
		(fp_line
			(start -0.7874 0.4064)
			(end -0.7874 -0.4064)
			(stroke
				(width 0.1524)
				(type default)
			)
			(layer "F.SilkS")
		)
		(fp_line
			(start -0.7874 -0.4064)
			(end 0.7874 -0.4064)
			(stroke
				(width 0.1524)
				(type default)
			)
			(layer "F.SilkS")
		)
		(fp_line
			(start 0.67945 0.3048)
			(end 0.120396 0.3048)
			(stroke
				(width 0.1)
				(type default)
			)
			(layer "F.Fab")
		)
		(fp_line
			(start 0.67945 -0.3048)
			(end 0.67945 0.3048)
			(stroke
				(width 0.1)
				(type default)
			)
			(layer "F.Fab")
		)
		(fp_line
			(start 0.12065 -0.2794)
			(end 0.12065 -0.3048)
			(stroke
				(width 0.1)
				(type default)
			)
			(layer "F.Fab")
		)
		(fp_line
			(start 0.12065 -0.3048)
			(end 0.67945 -0.3048)
			(stroke
				(width 0.1)
				(type default)
			)
			(layer "F.Fab")
		)
		(fp_line
			(start 0.120396 0.3048)
			(end 0.120396 0.2794)
			(stroke
				(width 0.1)
				(type default)
			)
			(layer "F.Fab")
		)
		(fp_line
			(start 0.120396 0.2794)
			(end -0.12065 0.2794)
			(stroke
				(width 0.1)
				(type default)
			)
			(layer "F.Fab")
		)
		(fp_line
			(start -0.12065 0.3048)
			(end -0.67945 0.3048)
			(stroke
				(width 0.1)
				(type default)
			)
			(layer "F.Fab")
		)
		(fp_line
			(start -0.12065 0.2794)
			(end -0.12065 0.3048)
			(stroke
				(width 0.1)
				(type default)
			)
			(layer "F.Fab")
		)
		(fp_line
			(start -0.12065 -0.2794)
			(end 0.12065 -0.2794)
			(stroke
				(width 0.1)
				(type default)
			)
			(layer "F.Fab")
		)
		(fp_line
			(start -0.12065 -0.305054)
			(end -0.12065 -0.2794)
			(stroke
				(width 0.1)
				(type default)
			)
			(layer "F.Fab")
		)
		(fp_line
			(start -0.67945 0.3048)
			(end -0.67945 -0.305054)
			(stroke
				(width 0.1)
				(type default)
			)
			(layer "F.Fab")
		)
		(fp_line
			(start -0.67945 -0.305054)
			(end -0.12065 -0.305054)
			(stroke
				(width 0.1)
				(type default)
			)
			(layer "F.Fab")
		)
		(pad "1" smd circle
			(at -0.40005 0 180)
			(size 0 0)
			(layers "F.Cu" "F.Mask" "F.Paste")
			(net "A_P12V_STBY_FP_TRIGGER")
		)
		(pad "2" smd circle
			(at 0.40005 0 180)
			(size 0 0)
			(layers "F.Cu" "F.Mask" "F.Paste")
			(net "GND")
		)
	)
)
